# S9S_MB_2U (Grand Teton) — schematic parts with pin connectivity, parts 5880–5880 of 6093; source: Cadence DE-HDL packaged netlist (pstxprt.dat, pstxnet.dat, pstchip.dat)

U2  SOCKET4677_AZIF0045P001C01CS  SOCKET4677_AZIF0045-P001C01CS IO  pkg SOCKET4677_82X64-5XA_H466  page 13  (pins 1305-1630 of 4677)
  BN48  VCCIN42  POWER  = PVCCIN_CPU0
  BN50  VCCIN43  POWER  = PVCCIN_CPU0
  BN52  VCCIN44  POWER  = PVCCIN_CPU0
  BN54  VCCIN45  POWER  = PVCCIN_CPU0
  BN56  VCCIN46  POWER  = PVCCIN_CPU0
  BN58  VCCIN47  POWER  = PVCCIN_CPU0
  BN60  VCCIN48  POWER  = PVCCIN_CPU0
  BN62  VSS519  POWER  = GND
  BN64  PKG_ID2  IN  = FM_CPU0_PKGID2
  BN66  PTI_DIE0115  OUT  = TP_TRC_CPU0_PTI<31>
  BN68  PTI_DIE0110  OUT  = TP_TRC_CPU0_PTI<26>
  BN70  VSS520  POWER  = GND
  BN72  UPI2_TX_DP23  OUT  = UPI_CPU0_CPU1_P2P2_DP<0>
  BN74  UPI2_RX_DN21  IN  = UPI_CPU1_CPU0_P2P2_DP<2>
  BN76  UPI2_RX_DP19  IN  = UPI_CPU1_CPU0_P2P2_DN<4>
  BN78  VCCIN49  POWER  = PVCCIN_CPU0
  BN80  VCCIN50  POWER  = PVCCIN_CPU0
  BN82  VCCIN51  POWER  = PVCCIN_CPU0
  BN84  VCCIN52  POWER  = PVCCIN_CPU0
  BN86  VCCIN53  POWER  = PVCCIN_CPU0
  BN88  VCCIN54  POWER  = PVCCIN_CPU0
  BN90  VCCIN55  POWER  = PVCCIN_CPU0
  BP2  VSS524  POWER  = GND
  BP4  VSS527  POWER  = GND
  BP6  UPI0_RX_DP22  IN  = UPI_CPU1_CPU0_P1P0_DP<22>
  BP8  VSS533  POWER  = GND
  BP10  PE1_RX_DN10  IN  = P5E_CPU0_PE1_RX_DN<10>
  BP12  VSS522  POWER  = GND
  BP14  PE1_TX_DN10  OUT  = P5E_CPU0_PE1_TX_DN<10>
  BP16  VSS523  POWER  = GND
  BP18  DMI_RX_DN6  IN  = DMI_CPU0_PCH_RX_C_DP<6>
  BP20  VSS525  POWER  = GND
  BP22  RSVD67  BI  = NC_CPU0_MDFI_DIE00_EW0
  BP24  CATERR_N  BI  = H_CPU0_CATERR_LVC1_R_N
  BP26  PRDY_N  OUT  = H_CPU0_PRDY_QS_GTL_R_N
  BP28  PTI_DIE0013  OUT  = TP_TRC_CPU0_PTI<13>
  BP30  PTI_DIE0015  OUT  = TP_TRC_CPU0_PTI<15>
  BP32  VCCIN56  POWER  = PVCCIN_CPU0
  BP34  VCCIN57  POWER  = PVCCIN_CPU0
  BP36  VCCIN58  POWER  = PVCCIN_CPU0
  BP38  VCCIN59  POWER  = PVCCIN_CPU0
  BP40  VCCIN60  POWER  = PVCCIN_CPU0
  BP42  VCCIN61  POWER  = PVCCIN_CPU0
  BP44  VCCIN62  POWER  = PVCCIN_CPU0
  BP47  VCCIN63  POWER  = PVCCIN_CPU0
  BP49  VCCIN64  POWER  = PVCCIN_CPU0
  BP51  VCCIN65  POWER  = PVCCIN_CPU0
  BP53  VCCIN66  POWER  = PVCCIN_CPU0
  BP55  VCCIN67  POWER  = PVCCIN_CPU0
  BP57  VCCIN68  POWER  = PVCCIN_CPU0
  BP59  VCCIN69  POWER  = PVCCIN_CPU0
  BP61  VCCIN70  POWER  = PVCCIN_CPU0
  BP63  VSS528  POWER  = GND
  BP65  RSVD68  BI  = NC_CPU0_SOC_SPARE5
  BP67  RSVD69  BI  = NC_CPU0_VIEWPIN_DIE01<1>
  BP69  RSVD70  BI  = NC_CPU0_VIEWPIN_DIE01<0>
  BP71  VSS529  POWER  = GND
  BP73  VSS530  POWER  = GND
  BP75  VSS531  POWER  = GND
  BP77  VSS532  POWER  = GND
  BP79  VCCIN71  POWER  = PVCCIN_CPU0
  BP81  VCCIN72  POWER  = PVCCIN_CPU0
  BP83  VCCIN73  POWER  = PVCCIN_CPU0
  BP85  VCCIN74  POWER  = PVCCIN_CPU0
  BP87  VCCIN75  POWER  = PVCCIN_CPU0
  BP89  VCCIN76  POWER  = PVCCIN_CPU0
  BR3  UPI0_TX_DN22  OUT  = UPI_CPU0_CPU1_P0P1_DP<22>
  BR5  VSS0  POWER  = GND
  BR7  UPI0_RX_DN22  IN  = UPI_CPU1_CPU0_P1P0_DN<22>
  BR9  VSS572  POWER  = GND
  BR11  PE1_RX_DN9  IN  = P5E_CPU0_PE1_RX_DN<9>
  BR13  VSS535  POWER  = GND
  BR15  PE1_TX_DP10  OUT  = P5E_CPU0_PE1_TX_DP<10>
  BR17  VSS536  POWER  = GND
  BR19  DMI_RX_DP6  IN  = DMI_CPU0_PCH_RX_C_DN<6>
  BR21  RSVD71  BI  = NC_CPU0_MDFI_DIE00_EW1
  BR23  RSVD72  BI  = TP_CPU0_BR23
  BR25  TMS  IN  = JTAG_DBP_CPU0_QS_GTL_R_TMS
  BR27  VSS538  POWER  = GND
  BR29  VSS539  POWER  = GND
  BR31  VSS540  POWER  = GND
  BR33  VSS541  POWER  = GND
  BR35  VSS542  POWER  = GND
  BR37  VSS543  POWER  = GND
  BR39  VSS545  POWER  = GND
  BR41  VSS546  POWER  = GND
  BR43  VSS547  POWER  = GND
  BR45  VSS548  POWER  = GND
  BR48  VSS549  POWER  = GND
  BR50  VSS550  POWER  = GND
  BR52  VSS551  POWER  = GND
  BR54  VSS552  POWER  = GND
  BR56  VSS555  POWER  = GND
  BR58  VSS556  POWER  = GND
  BR60  VCCIN77  POWER  = PVCCIN_CPU0
  BR62  VCCIN78  POWER  = PVCCIN_CPU0
  BR64  VSS557  POWER  = GND
  BR66  VSS559  POWER  = GND
  BR68  VSS560  POWER  = GND
  BR70  VSS561  POWER  = GND
  BR72  VSS563  POWER  = GND
  BR74  VSS564  POWER  = GND
  BR76  VSS565  POWER  = GND
  BR78  VCCIN79  POWER  = PVCCIN_CPU0
  BR80  VSS566  POWER  = GND
  BR82  VSS567  POWER  = GND
  BR84  VSS568  POWER  = GND
  BR86  VSS569  POWER  = GND
  BR88  VSS570  POWER  = GND
  BR90  VSS573  POWER  = GND
  BT2  UPI0_TX_DN23  OUT  = UPI_CPU0_CPU1_P0P1_DN<23>
  BT4  VSS577  POWER  = GND
  BT6  UPI0_RX_DP23  IN  = UPI_CPU1_CPU0_P1P0_DN<23>
  BT8  VSS578  POWER  = GND
  BT10  PE1_RX_DP9  IN  = P5E_CPU0_PE1_RX_DP<9>
  BT12  VSS574  POWER  = GND
  BT14  PE1_TX_DP9  OUT  = P5E_CPU0_PE1_TX_DP<9>
  BT16  VSS575  POWER  = GND
  BT18  DMI_RX_DP7  IN  = DMI_CPU0_PCH_RX_C_DP<7>
  BT20  VSS576  POWER  = GND
  BT22  DDR0123_SPDSCL  OUT  = I3C_SPD_DDRABCD_CPU0_SCL
  BT24  TCK  IN  = JTAG_DBP_CPU0_GTL_R_TCK
  BT26  TXT_AGENT  IN  = PU_CPU0_TXT_AGENT
  BT28  PTI_DIE009  OUT  = TP_TRC_CPU0_PTI<9>
  BT30  PTI_DIE0011  OUT  = TP_TRC_CPU0_PTI<11>
  BT32  VCCIN80  POWER  = PVCCIN_CPU0
  BT34  VCCIN81  POWER  = PVCCIN_CPU0
  BT36  VCCIN82  POWER  = PVCCIN_CPU0
  BT38  VCCIN83  POWER  = PVCCIN_CPU0
  BT40  VCCIN84  POWER  = PVCCIN_CPU0
  BT42  VCCIN85  POWER  = PVCCIN_CPU0
  BT44  VCCIN86  POWER  = PVCCIN_CPU0
  BT47  VCCIN87  POWER  = PVCCIN_CPU0
  BT49  VCCIN88  POWER  = PVCCIN_CPU0
  BT51  VCCIN89  POWER  = PVCCIN_CPU0
  BT53  VCCIN90  POWER  = PVCCIN_CPU0
  BT55  VCCIN91  POWER  = PVCCIN_CPU0
  BT57  VCCIN92  POWER  = PVCCIN_CPU0
  BT59  VCCIN93  POWER  = PVCCIN_CPU0
  BT61  VCCIN94  POWER  = PVCCIN_CPU0
  BT63  VCCIN95  POWER  = PVCCIN_CPU0
  BT65  VCCIN96  POWER  = PVCCIN_CPU0
  BT67  VCCIN97  POWER  = PVCCIN_CPU0
  BT69  VCCIN98  POWER  = PVCCIN_CPU0
  BT71  VCCIN99  POWER  = PVCCIN_CPU0
  BT73  VCCIN100  POWER  = PVCCIN_CPU0
  BT75  VCCIN101  POWER  = PVCCIN_CPU0
  BT77  VCCIN102  POWER  = PVCCIN_CPU0
  BT79  VCCIN103  POWER  = PVCCIN_CPU0
  BT81  VCCIN104  POWER  = PVCCIN_CPU0
  BT83  VCCIN105  POWER  = PVCCIN_CPU0
  BT85  VCCIN106  POWER  = PVCCIN_CPU0
  BT87  VCCIN107  POWER  = PVCCIN_CPU0
  BT89  VCCIN108  POWER  = PVCCIN_CPU0
  BU3  UPI0_TX_DP23  OUT  = UPI_CPU0_CPU1_P0P1_DP<23>
  BU5  UPI0_RX_DN23  IN  = UPI_CPU1_CPU0_P1P0_DP<23>
  BU7  VSS586  POWER  = GND
  BU9  PE1_RX_DP8  IN  = P5E_CPU0_PE1_RX_DP<8>
  BU11  VCCD_HV_SENSE  POWER  = VSENSE_PVCCD_HV_CPU0_DP
  BU13  PE1_TX_DN9  OUT  = P5E_CPU0_PE1_TX_DN<9>
  BU15  VSS579  POWER  = GND
  BU17  DMI_RX_DN7  IN  = DMI_CPU0_PCH_RX_C_DN<7>
  BU19  VSS580  POWER  = GND
  BU21  VSS581  POWER  = GND
  BU23  VSS582  POWER  = GND
  BU25  VSS584  POWER  = GND
  BU27  PTI_DIE008  OUT  = TP_TRC_CPU0_PTI<8>
  BU29  PTI_DIE0010  OUT  = TP_TRC_CPU0_PTI<10>
  BU31  VSS585  POWER  = GND
  BU33  VCCIN109  POWER  = PVCCIN_CPU0
  BU35  VCCIN110  POWER  = PVCCIN_CPU0
  BU37  VCCIN111  POWER  = PVCCIN_CPU0
  BU39  VCCIN112  POWER  = PVCCIN_CPU0
  BU41  VCCIN113  POWER  = PVCCIN_CPU0
  BU43  VCCIN114  POWER  = PVCCIN_CPU0
  BU45  VCCIN115  POWER  = PVCCIN_CPU0
  BU48  VCCIN116  POWER  = PVCCIN_CPU0
  BU50  VCCIN117  POWER  = PVCCIN_CPU0
  BU52  VCCIN118  POWER  = PVCCIN_CPU0
  BU54  VCCIN119  POWER  = PVCCIN_CPU0
  BU56  VCCIN120  POWER  = PVCCIN_CPU0
  BU58  VCCIN121  POWER  = PVCCIN_CPU0
  BU60  VCCIN122  POWER  = PVCCIN_CPU0
  BU62  VCCIN123  POWER  = PVCCIN_CPU0
  BU64  VCCIN124  POWER  = PVCCIN_CPU0
  BU66  VCCIN125  POWER  = PVCCIN_CPU0
  BU68  VCCIN126  POWER  = PVCCIN_CPU0
  BU70  VCCIN127  POWER  = PVCCIN_CPU0
  BU72  VCCIN128  POWER  = PVCCIN_CPU0
  BU74  VCCIN129  POWER  = PVCCIN_CPU0
  BU76  VCCIN130  POWER  = PVCCIN_CPU0
  BU78  VCCIN131  POWER  = PVCCIN_CPU0
  BU80  VCCIN132  POWER  = PVCCIN_CPU0
  BU82  VCCIN133  POWER  = PVCCIN_CPU0
  BU84  VCCIN134  POWER  = PVCCIN_CPU0
  BU86  VCCIN135  POWER  = PVCCIN_CPU0
  BU88  VCCIN136  POWER  = PVCCIN_CPU0
  BU90  VCCIN137  POWER  = PVCCIN_CPU0
  BV2  VSS590  POWER  = GND
  BV4  VSS592  POWER  = GND
  BV6  VSS593  POWER  = GND
  BV8  VSS594  POWER  = GND
  BV10  PE1_RX_DN8  IN  = P5E_CPU0_PE1_RX_DN<8>
  BV12  VSS587  POWER  = GND
  BV14  PE1_TX_DN8  OUT  = P5E_CPU0_PE1_TX_DN<8>
  BV16  VSS588  POWER  = GND
  BV18  VSS589  POWER  = GND
  BV20  VSS591  POWER  = GND
  BV22  RSVD73  BI  = NC_CPU0_UPI1_APROBE<0>
  BV24  TDI  IN  = JTAG_DBP_CPU0_GTL_R_TDI
  BV26  CXPSMBUS_ALERT_N  IN  = FM_PEHPCPU0_ALERT_N
  BV28  PTI_DIE007  OUT  = TP_TRC_CPU0_PTI<7>
  BV30  PTI_DIE005  OUT  = TP_TRC_CPU0_PTI<5>
  BV32  VCCIN138  POWER  = PVCCIN_CPU0
  BV34  VCCIN139  POWER  = PVCCIN_CPU0
  BV36  VCCIN140  POWER  = PVCCIN_CPU0
  BV38  VCCIN141  POWER  = PVCCIN_CPU0
  BV40  VCCIN142  POWER  = PVCCIN_CPU0
  BV42  VCCIN143  POWER  = PVCCIN_CPU0
  BV44  VCCIN144  POWER  = PVCCIN_CPU0
  BV47  VCCIN145  POWER  = PVCCIN_CPU0
  BV49  VCCIN146  POWER  = PVCCIN_CPU0
  BV51  VCCIN147  POWER  = PVCCIN_CPU0
  BV53  VCCIN148  POWER  = PVCCIN_CPU0
  BV55  VCCIN149  POWER  = PVCCIN_CPU0
  BV57  VCCIN150  POWER  = PVCCIN_CPU0
  BV59  VCCIN151  POWER  = PVCCIN_CPU0
  BV61  VCCIN152  POWER  = PVCCIN_CPU0
  BV63  VCCIN153  POWER  = PVCCIN_CPU0
  BV65  VCCIN154  POWER  = PVCCIN_CPU0
  BV67  VCCIN155  POWER  = PVCCIN_CPU0
  BV69  VCCIN156  POWER  = PVCCIN_CPU0
  BV71  VCCIN157  POWER  = PVCCIN_CPU0
  BV73  VCCIN158  POWER  = PVCCIN_CPU0
  BV75  VCCIN159  POWER  = PVCCIN_CPU0
  BV77  VCCIN160  POWER  = PVCCIN_CPU0
  BV79  VCCIN161  POWER  = PVCCIN_CPU0
  BV81  VCCIN162  POWER  = PVCCIN_CPU0
  BV83  VCCIN163  POWER  = PVCCIN_CPU0
  BV85  VCCIN164  POWER  = PVCCIN_CPU0
  BV87  VCCIN165  POWER  = PVCCIN_CPU0
  BV89  VCCIN166  POWER  = PVCCIN_CPU0
  BW3  VSS600  POWER  = GND
  BW5  VSS602  POWER  = GND
  BW7  UPI1_TX_DP23  OUT  = UPI_CPU0_CPU1_P1P0_DN<23>
  BW9  VSS603  POWER  = GND
  BW11  PE1_RX_DN7  IN  = P5E_CPU0_PE1_RX_DN<7>
  BW13  VSS596  POWER  = GND
  BW15  PE1_TX_DP8  OUT  = P5E_CPU0_PE1_TX_DP<8>
  BW17  VSS597  POWER  = GND
  BW19  DMI_TX_DN0  OUT  = DMI_CPU0_PCH_TX_DP<0>
  BW21  RSVD74  BI  = NC_CPU0_DMI_APROBE<1>
  BW23  RSVD75  BI  = NC_CPU0_PE2_APROBE<1>
  BW25  TDO  OUT  = JTAG_CPU0_MUX_GTL_TDO
  BW27  VSS598  POWER  = GND
  BW29  VSS599  POWER  = GND
  BW31  VSS601  POWER  = GND
  BW33  VCCIN167  POWER  = PVCCIN_CPU0
  BW35  VCCIN168  POWER  = PVCCIN_CPU0
  BW37  VCCIN169  POWER  = PVCCIN_CPU0
  BW39  VCCIN170  POWER  = PVCCIN_CPU0
  BW41  VCCIN171  POWER  = PVCCIN_CPU0
  BW43  VCCIN172  POWER  = PVCCIN_CPU0
  BW45  VCCIN173  POWER  = PVCCIN_CPU0
  BW48  VCCIN174  POWER  = PVCCIN_CPU0
  BW50  VCCIN175  POWER  = PVCCIN_CPU0
  BW52  VCCIN176  POWER  = PVCCIN_CPU0
  BW54  VCCIN177  POWER  = PVCCIN_CPU0
  BW56  VCCIN178  POWER  = PVCCIN_CPU0
  BW58  VCCIN179  POWER  = PVCCIN_CPU0
  BW60  VCCIN180  POWER  = PVCCIN_CPU0
  BW62  VCCIN181  POWER  = PVCCIN_CPU0
  BW64  VCCIN182  POWER  = PVCCIN_CPU0
  BW66  VCCIN183  POWER  = PVCCIN_CPU0
  BW68  VCCIN184  POWER  = PVCCIN_CPU0
  BW70  VCCIN185  POWER  = PVCCIN_CPU0
  BW72  VCCIN186  POWER  = PVCCIN_CPU0
  BW74  VCCIN187  POWER  = PVCCIN_CPU0
  BW76  VCCIN188  POWER  = PVCCIN_CPU0
  BW78  VCCIN189  POWER  = PVCCIN_CPU0
  BW80  VCCIN190  POWER  = PVCCIN_CPU0
  BW82  VCCIN191  POWER  = PVCCIN_CPU0
  BW84  VCCIN192  POWER  = PVCCIN_CPU0
  BW86  VCCIN193  POWER  = PVCCIN_CPU0
  BW88  VCCIN194  POWER  = PVCCIN_CPU0
  BW90  VCCIN195  POWER  = PVCCIN_CPU0
  BY2  UPI1_RX_DP23  IN  = UPI_CPU1_CPU0_P0P1_DN<23>
  BY4  VSS607  POWER  = GND
  BY6  UPI1_TX_DN23  OUT  = UPI_CPU0_CPU1_P1P0_DP<23>
  BY8  VSS608  POWER  = GND
  BY10  PE1_RX_DP7  IN  = P5E_CPU0_PE1_RX_DP<7>
  BY12  VSS604  POWER  = GND
  BY14  PE1_TX_DP7  OUT  = P5E_CPU0_PE1_TX_DP<7>
  BY16  VSS605  POWER  = GND
  BY18  DMI_TX_DP1  OUT  = DMI_CPU0_PCH_TX_DN<1>
  BY20  VSS606  POWER  = GND
  BY22  DDR0123_SPDSDA  BI  = I3C_SPD_DDRABCD_CPU0_SDA
  BY24  RSVD76  BI  = PD_EXT_CLK_SEL_CPU0
  BY26  CXPSMBUSSDA  BI  = SMB_PEHPCPU0_GTL_SDA
  BY28  PTI_DIE00_STB_1  OUT  = TP_TRC_CPU0_PTI1_CLK
  BY30  PTI_DIE003  OUT  = TP_TRC_CPU0_PTI<3>
  BY32  VCCIN196  POWER  = PVCCIN_CPU0
  BY34  VCCIN197  POWER  = PVCCIN_CPU0
  BY36  VCCIN198  POWER  = PVCCIN_CPU0
  BY38  VCCIN199  POWER  = PVCCIN_CPU0
  BY40  VCCIN200  POWER  = PVCCIN_CPU0
  BY42  VCCIN201  POWER  = PVCCIN_CPU0
  BY44  VCCIN202  POWER  = PVCCIN_CPU0
  BY47  VCCIN203  POWER  = PVCCIN_CPU0
  BY49  VCCIN204  POWER  = PVCCIN_CPU0
  BY51  VCCIN205  POWER  = PVCCIN_CPU0
  BY53  VCCIN206  POWER  = PVCCIN_CPU0
  BY55  VCCIN207  POWER  = PVCCIN_CPU0
  BY57  VCCIN208  POWER  = PVCCIN_CPU0
  BY59  VCCIN209  POWER  = PVCCIN_CPU0
  BY61  VCCIN210  POWER  = PVCCIN_CPU0
  BY63  VCCIN211  POWER  = PVCCIN_CPU0
  BY65  VCCIN212  POWER  = PVCCIN_CPU0
  BY67  VCCIN213  POWER  = PVCCIN_CPU0
  BY69  VCCIN214  POWER  = PVCCIN_CPU0
  BY71  VCCIN215  POWER  = PVCCIN_CPU0
  BY73  VCCIN216  POWER  = PVCCIN_CPU0
  BY75  VCCIN217  POWER  = PVCCIN_CPU0
  BY77  VCCIN218  POWER  = PVCCIN_CPU0
  BY79  VCCIN219  POWER  = PVCCIN_CPU0
  BY81  VCCIN220  POWER  = PVCCIN_CPU0
